# T6G (Grand Teton) — schematic netlist excerpt (pin names and nets, part order shuffled) for the footprints in the layout excerpt that follows; sources: Cadence DE-HDL packaged netlist, KiCad conversion of 04192023_DAF0TMB3IC0_F0TG_MB_C_brd_V02_OCP.brd

J26  SCONN288_DDR506112002KQ  IO  pkg DDR288S_1-1VXC  page 99
  VIN_BULK0  = P12V_MEM_CPU1
  RFU0  = NC
  VIN_MGMT  = P3V3_AUX
  HSCL  = I3C_SPD_DDRB_CPU1_SCL
  HSDA  = I3C_SPD_DDRB_CPU1_SDA
  VSS0  = GND
  DQ0_A  = M_B_CPU1_SA_DQ<0>
  VSS1  = GND
  DQ1_A  = M_B_CPU1_SA_DQ<1>
  VSS2  = GND
  DQS0_A_T  = M_B_CPU1_SA_DQS_DP<0>
  DQS0_A_C  = M_B_CPU1_SA_DQS_DN<0>
  VSS3  = GND
  DQ4_A  = M_B_CPU1_SA_DQ<4>
  VSS4  = GND
  DQ5_A  = M_B_CPU1_SA_DQ<5>
  VSS5  = GND
  DQ8_A  = M_B_CPU1_SA_DQ<8>
  VSS6  = GND
  DQ9_A  = M_B_CPU1_SA_DQ<9>
  VSS7  = GND
  DQS1_A_T  = M_B_CPU1_SA_DQS_DP<1>
  DQS1_A_C  = M_B_CPU1_SA_DQS_DN<1>
  VSS8  = GND
  DQ12_A  = M_B_CPU1_SA_DQ<12>
  VSS9  = GND
  DQ13_A  = M_B_CPU1_SA_DQ<13>
  VSS10  = GND
  DQ16_A  = M_B_CPU1_SA_DQ<16>
  VSS11  = GND
  DQ17_A  = M_B_CPU1_SA_DQ<17>
  VSS12  = GND
  DQS2_A_T  = M_B_CPU1_SA_DQS_DP<2>
  DQS2_A_C  = M_B_CPU1_SA_DQS_DN<2>
  VSS13  = GND
  DQ20_A  = M_B_CPU1_SA_DQ<20>
  VSS14  = GND
  DQ21_A  = M_B_CPU1_SA_DQ<21>
  VSS15  = GND
  DQ24_A  = M_B_CPU1_SA_DQ<24>
  VSS16  = GND
  DQ25_A  = M_B_CPU1_SA_DQ<25>
  VSS17  = GND
  DQS3_A_T  = M_B_CPU1_SA_DQS_DP<3>
  DQS3_A_C  = M_B_CPU1_SA_DQS_DN<3>
  VSS18  = GND
  DQ28_A  = M_B_CPU1_SA_DQ<28>
  VSS19  = GND
  DQ29_A  = M_B_CPU1_SA_DQ<29>
  VSS20  = GND
  CB0_A  = M_B_CPU1_SA_CB<0>
  VSS21  = GND
  CB1_A  = M_B_CPU1_SA_CB<1>
  VSS22  = GND
  DQS4_A_T  = M_B_CPU1_SA_DQS_DP<4>
  DQS4_A_C  = M_B_CPU1_SA_DQS_DN<4>
  VSS23  = GND
  CB4_A  = M_B_CPU1_SA_CB<4>
  VSS24  = GND
  CB5_A  = M_B_CPU1_SA_CB<5>
  VSS25  = GND
  ALERT_N  = M_B_CPU1_ALERT_N
  VSS26  = GND
  CS0_A_N  = M_B_CPU1_SA_CS_N<0>
  VSS27  = GND
  CA0_A  = M_B_CPU1_SA_CA<0>
  VSS28  = GND
  CA2_A  = M_B_CPU1_SA_CA<2>
  VSS29  = GND
  CA4_A  = M_B_CPU1_SA_CA<4>
  VSS30  = GND
  CA6_A  = M_B_CPU1_SA_CA<6>
  VSS31  = GND
  PAR_A  = M_B_CPU1_SA_PAR
  VSS32  = GND
  CA0_B  = M_B_CPU1_SB_CA<0>
  VSS33  = GND
  CA2_B  = M_B_CPU1_SB_CA<2>
  VSS34  = GND
  CA4_B  = M_B_CPU1_SB_CA<4>
  VSS35  = GND
  CA6_B  = M_B_CPU1_SB_CA<6>
  VSS36  = GND
  CS0_B_N  = M_B_CPU1_SB_CS_N<0>
  VSS37  = GND
  \lbd||rsp_a_n\  = M_B_CPU1_SA_RSP<0>
  \lbs||rsp_b_n\  = M_B_CPU1_SB_RSP<0>
  VSS38  = GND
  CB4_B  = M_B_CPU1_SB_CB<4>
  VSS39  = GND
  CB5_B  = M_B_CPU1_SB_CB<5>
  VSS40  = GND
  \dqs9_b_t||tdqs9_b_t||dbi4_b_n\  = M_B_CPU1_SB_DQS_DP<9>
  \dqs9_b_c||tdqs9_b_c\  = M_B_CPU1_SB_DQS_DN<9>
  VSS41  = GND
  CB0_B  = M_B_CPU1_SB_CB<0>
  VSS42  = GND
  CB1_B  = M_B_CPU1_SB_CB<1>
  VSS43  = GND
  DQ0_B  = M_B_CPU1_SB_DQ<0>
  VSS44  = GND
  DQ1_B  = M_B_CPU1_SB_DQ<1>
  VSS45  = GND
  DQS0_B_T  = M_B_CPU1_SB_DQS_DP<0>
  DQS0_B_C  = M_B_CPU1_SB_DQS_DN<0>
  VSS46  = GND
  DQ4_B  = M_B_CPU1_SB_DQ<4>
  VSS47  = GND
  DQ5_B  = M_B_CPU1_SB_DQ<5>
  VSS48  = GND
  DQ8_B  = M_B_CPU1_SB_DQ<8>
  VSS49  = GND
  DQ9_B  = M_B_CPU1_SB_DQ<9>
  VSS50  = GND
  DQS1_B_T  = M_B_CPU1_SB_DQS_DP<1>
  DQS1_B_C  = M_B_CPU1_SB_DQS_DN<1>
  VSS51  = GND
  DQ12_B  = M_B_CPU1_SB_DQ<12>
  VSS52  = GND
  DQ13_B  = M_B_CPU1_SB_DQ<13>
  VSS53  = GND
  DQ16_B  = M_B_CPU1_SB_DQ<16>
  VSS54  = GND
  DQ17_B  = M_B_CPU1_SB_DQ<17>
  VSS55  = GND
  DQS2_B_T  = M_B_CPU1_SB_DQS_DP<2>
  DQS2_B_C  = M_B_CPU1_SB_DQS_DN<2>
  VSS56  = GND
  DQ20_B  = M_B_CPU1_SB_DQ<20>
  VSS57  = GND
  DQ21_B  = M_B_CPU1_SB_DQ<21>
  VSS58  = GND
  DQ24_B  = M_B_CPU1_SB_DQ<24>
  VSS59  = GND
  DQ25_B  = M_B_CPU1_SB_DQ<25>
  VSS60  = GND
  DQS3_B_T  = M_B_CPU1_SB_DQS_DP<3>
  DQS3_B_C  = M_B_CPU1_SB_DQS_DN<3>
  VSS61  = GND
  DQ28_B  = M_B_CPU1_SB_DQ<28>
  VSS62  = GND
  DQ29_B  = M_B_CPU1_SB_DQ<29>
  VSS63  = GND
  RFU1  = NC
  VIN_BULK1  = P12V_MEM_CPU1
  VIN_BULK2  = P12V_MEM_CPU1
  \pwr_good||fail_n\  = PWRGD_CHB_CPU1_DIMM
  HAS  = PD_CHB_CPU1_DIMM_SAA
  RFU2  = NC
  RFU3  = NC
  VSS64  = GND
  DQ2_A  = M_B_CPU1_SA_DQ<2>
  VSS65  = GND
  DQ3_A  = M_B_CPU1_SA_DQ<3>
  VSS66  = GND
  \dqs5_a_c||tdqs5_a_c||dqs5_a_t||tdqs5_a_t\  = M_B_CPU1_SA_DQS_DN<5>
  \dqs5_a_t||tdqs5_a_t\  = M_B_CPU1_SA_DQS_DP<5>
  VSS67  = GND
  DQ6_A  = M_B_CPU1_SA_DQ<6>
  VSS68  = GND
  DQ7_A  = M_B_CPU1_SA_DQ<7>
  VSS69  = GND
  DQ10_A  = M_B_CPU1_SA_DQ<10>
  VSS70  = GND
  DQ11_A  = M_B_CPU1_SA_DQ<11>
  VSS71  = GND
  \dqs6_a_c||tdqs6_a_c||dqs6_a_t||tdqs6_a_t\  = M_B_CPU1_SA_DQS_DN<6>
  \dqs6_a_t||tdqs6_a_t\  = M_B_CPU1_SA_DQS_DP<6>
  VSS72  = GND
  DQ14_A  = M_B_CPU1_SA_DQ<14>
  VSS73  = GND
  DQ15_A  = M_B_CPU1_SA_DQ<15>
  VSS74  = GND
  DQ18_A  = M_B_CPU1_SA_DQ<18>
  VSS75  = GND
  DQ19_A  = M_B_CPU1_SA_DQ<19>
  VSS76  = GND
  \dqs7_a_c||tdqs7_a_c\  = M_B_CPU1_SA_DQS_DN<7>
  \dqs7_a_t||tdqs7_a_t\  = M_B_CPU1_SA_DQS_DP<7>
  VSS77  = GND
  DQ22_A  = M_B_CPU1_SA_DQ<22>
  VSS78  = GND
  DQ23_A  = M_B_CPU1_SA_DQ<23>
  VSS79  = GND
  DQ26_A  = M_B_CPU1_SA_DQ<26>
  VSS80  = GND
  DQ27_A  = M_B_CPU1_SA_DQ<27>
  VSS81  = GND
  \dqs8_a_c||tdqs8_a_c\  = M_B_CPU1_SA_DQS_DN<8>
  \dqs8_a_t||tdqs8_a_t\  = M_B_CPU1_SA_DQS_DP<8>
  VSS82  = GND
  DQ30_A  = M_B_CPU1_SA_DQ<30>
  VSS83  = GND
  DQ31_A  = M_B_CPU1_SA_DQ<31>
  VSS84  = GND
  CB2_A  = M_B_CPU1_SA_CB<2>
  VSS85  = GND
  CB3_A  = M_B_CPU1_SA_CB<3>
  VSS86  = GND
  \dqs9_a_c||tdqs9_a_c\  = M_B_CPU1_SA_DQS_DN<9>
  \dqs9_a_t||tdqs9_a_t\  = M_B_CPU1_SA_DQS_DP<9>
  VSS87  = GND
  CB6_A  = M_B_CPU1_SA_CB<6>
  VSS88  = GND
  CB7_A  = M_B_CPU1_SA_CB<7>
  VSS89  = GND
  RESET_N  = M_B_CPU1_RESET_N
  VSS90  = GND
  CS1_A_N  = M_B_CPU1_SA_CS_N<1>
  VSS91  = GND
  CA1_A  = M_B_CPU1_SA_CA<1>
  VSS92  = GND
  CA3_A  = M_B_CPU1_SA_CA<3>
  VSS93  = GND
  CA5_A  = M_B_CPU1_SA_CA<5>
  VSS94  = GND
  CK_T  = M_B_CPU1_CLK_DP<0>
  CK_C  = M_B_CPU1_CLK_DN<0>
  VSS95  = GND
  RFU4  = NC
  CA1_B  = M_B_CPU1_SB_CA<1>
  VSS96  = GND
  CA3_B  = M_B_CPU1_SB_CA<3>
  VSS97  = GND
  CA5_B  = M_B_CPU1_SB_CA<5>
  VSS98  = GND
  PAR_B  = M_B_CPU1_SB_PAR
  VSS99  = GND
  CS1_B_N  = M_B_CPU1_SB_CS_N<1>
  VSS100  = GND
  RFU5  = NC
  RFU6  = NC
  VSS101  = GND
  CB6_B  = M_B_CPU1_SB_CB<6>
  VSS102  = GND
  CB7_B  = M_B_CPU1_SB_CB<7>
  VSS103  = GND
  DQS4_B_C  = M_B_CPU1_SB_DQS_DN<4>
  DQS4_B_T  = M_B_CPU1_SB_DQS_DP<4>
  VSS104  = GND
  CB2_B  = M_B_CPU1_SB_CB<2>
  VSS105  = GND
  CB3_B  = M_B_CPU1_SB_CB<3>
  VSS106  = GND
  DQ2_B  = M_B_CPU1_SB_DQ<2>
  VSS107  = GND
  DQ3_B  = M_B_CPU1_SB_DQ<3>
  VSS108  = GND
  \dqs5_b_c||tdqs5_b_c\  = M_B_CPU1_SB_DQS_DN<5>
  \dqs5_b_t||tdqs5_b_t\  = M_B_CPU1_SB_DQS_DP<5>
  VSS109  = GND
  DQ6_B  = M_B_CPU1_SB_DQ<6>
  VSS110  = GND
  DQ7_B  = M_B_CPU1_SB_DQ<7>
  VSS111  = GND
  DQ10_B  = M_B_CPU1_SB_DQ<10>
  VSS112  = GND
  DQ11_B  = M_B_CPU1_SB_DQ<11>
  VSS113  = GND
  \dqs6_b_c||tdqs6_b_c\  = M_B_CPU1_SB_DQS_DN<6>
  \dqs6_b_t||tdqs6_b_t\  = M_B_CPU1_SB_DQS_DP<6>
  VSS114  = GND
  DQ14_B  = M_B_CPU1_SB_DQ<14>
  VSS115  = GND
  DQ15_B  = M_B_CPU1_SB_DQ<15>
  VSS116  = GND
  DQ18_B  = M_B_CPU1_SB_DQ<18>
  VSS117  = GND
  DQ19_B  = M_B_CPU1_SB_DQ<19>
  VSS118  = GND
  \dqs7_b_c||tdqs7_b_c\  = M_B_CPU1_SB_DQS_DN<7>
  \dqs7_b_t||tdqs7_b_t\  = M_B_CPU1_SB_DQS_DP<7>
  VSS119  = GND
  DQ22_B  = M_B_CPU1_SB_DQ<22>
  VSS120  = GND
  DQ23_B  = M_B_CPU1_SB_DQ<23>
  VSS121  = GND
  DQ26_B  = M_B_CPU1_SB_DQ<26>
  VSS122  = GND
  DQ27_B  = M_B_CPU1_SB_DQ<27>
  VSS123  = GND
  \dqs8_b_c||tdqs8_b_c\  = M_B_CPU1_SB_DQS_DN<8>
  \dqs8_b_t||tdqs8_b_t\  = M_B_CPU1_SB_DQS_DP<8>
  VSS124  = GND
  DQ30_B  = M_B_CPU1_SB_DQ<30>
  VSS125  = GND
  DQ31_B  = M_B_CPU1_SB_DQ<31>
  VSS126  = GND
  G1  = GND
  G2  = GND
  G3  = GND

(kicad_pcb
	(version 20260206)
	(generator "pcbnew")
	(generator_version "10.0")
	(general
		(thickness 1.6)
		(legacy_teardrops no)
	)
	(paper "A4")
	(title_block
		(title "04192023_DAF0TMB3IC0_F0TG_MB_C_brd_V02_OCP.brd")
		(comment 1 "Grand Teton / footprint 4371 of 8354 (J26), pads 185-230 of 291")
	)
	(layers
		(0 "F.Cu" signal "TOP")
		(4 "In1.Cu" signal "GND")
		(6 "In2.Cu" signal "IN1")
		(8 "In3.Cu" signal "GND1")
		(10 "In4.Cu" signal "IN2")
		(12 "In5.Cu" signal "GND2")
		(14 "In6.Cu" signal "IN3")
		(16 "In7.Cu" signal "GND3")
		(18 "In8.Cu" signal "VCC")
		(20 "In9.Cu" signal "VCC1")
		(22 "In10.Cu" signal "GND4")
		(24 "In11.Cu" signal "IN4")
		(26 "In12.Cu" signal "GND5")
		(28 "In13.Cu" signal "IN5")
		(30 "In14.Cu" signal "GND6")
		(32 "In15.Cu" signal "IN6")
		(34 "In16.Cu" signal "GND7")
		(2 "B.Cu" signal "BOTTOM")
		(9 "F.Adhes" user "F.Adhesive")
		(11 "B.Adhes" user "B.Adhesive")
		(13 "F.Paste" user "Package Geometry/Pastemask Top")
		(15 "B.Paste" user "Package Geometry/Pastemask Bottom")
		(5 "F.SilkS" user "Ref Des/Silkscreen Top")
		(7 "B.SilkS" user "Ref Des/Silkscreen Bottom")
		(1 "F.Mask" user "Board Geometry/Soldermask Top")
		(3 "B.Mask" user "Board Geometry/Soldermask Bottom")
		(17 "Dwgs.User" user "User.Drawings")
		(19 "Cmts.User" user "User.Comments")
		(21 "Eco1.User" user "User.Eco1")
		(23 "Eco2.User" user "User.Eco2")
		(25 "Edge.Cuts" user "Board Geometry/Outline")
		(27 "Margin" user)
		(31 "F.CrtYd" user "Package Geometry/Place Bound Top")
		(29 "B.CrtYd" user "Package Geometry/Place Bound Bottom")
		(35 "F.Fab" user "Ref Des/Assembly Top")
		(33 "B.Fab" user "Ref Des/Assembly Bottom")
	)
	(footprint ""
		(layer "F.Cu")
		(at 49.834038 -255.560322 180)
		(property "Reference" "J26"
			(at -0.703326 -82.357722 0)
			(unlocked yes)
			(layer "F.SilkS")
			(effects
				(font
					(size 0.7874 0.5842)
					(thickness 0.1524)
				)
			)
		)
		(property "Value" ""
			(at 0 0 180)
			(layer "F.Fab")
			(effects
				(font
					(size 1.27 1.27)
				)
			)
		)
		(duplicate_pad_numbers_are_jumpers no)
		(pad "185" smd rect
			(at 2.050034 -29.325062 90)
			(size 0.519938 1.4986)
			(layers "F.Cu" "F.Mask" "F.Paste")
			(net "M_B_CPU1_SA_DQ<26>")
		)
		(pad "186" smd rect
			(at 2.050034 -28.474924 90)
			(size 0.519938 1.4986)
			(layers "F.Cu" "F.Mask" "F.Paste")
			(net "GND")
		)
		(pad "187" smd rect
			(at 2.050034 -27.62504 90)
			(size 0.519938 1.4986)
			(layers "F.Cu" "F.Mask" "F.Paste")
			(net "M_B_CPU1_SA_DQ<27>")
		)
		(pad "188" smd rect
			(at 2.050034 -26.774902 90)
			(size 0.519938 1.4986)
			(layers "F.Cu" "F.Mask" "F.Paste")
			(net "GND")
		)
		(pad "189" smd rect
			(at 2.050034 -25.925018 90)
			(size 0.519938 1.4986)
			(layers "F.Cu" "F.Mask" "F.Paste")
			(net "M_B_CPU1_SA_DQS_DN<8>")
		)
		(pad "190" smd rect
			(at 2.050034 -25.07488 90)
			(size 0.519938 1.4986)
			(layers "F.Cu" "F.Mask" "F.Paste")
			(net "M_B_CPU1_SA_DQS_DP<8>")
		)
		(pad "191" smd rect
			(at 2.050034 -24.224996 90)
			(size 0.519938 1.4986)
			(layers "F.Cu" "F.Mask" "F.Paste")
			(net "GND")
		)
		(pad "192" smd rect
			(at 2.050034 -23.375112 90)
			(size 0.519938 1.4986)
			(layers "F.Cu" "F.Mask" "F.Paste")
			(net "M_B_CPU1_SA_DQ<30>")
		)
		(pad "193" smd rect
			(at 2.050034 -22.524974 90)
			(size 0.519938 1.4986)
			(layers "F.Cu" "F.Mask" "F.Paste")
			(net "GND")
		)
		(pad "194" smd rect
			(at 2.050034 -21.67509 90)
			(size 0.519938 1.4986)
			(layers "F.Cu" "F.Mask" "F.Paste")
			(net "M_B_CPU1_SA_DQ<31>")
		)
		(pad "195" smd rect
			(at 2.050034 -20.824952 90)
			(size 0.519938 1.4986)
			(layers "F.Cu" "F.Mask" "F.Paste")
			(net "GND")
		)
		(pad "196" smd rect
			(at 2.050034 -19.975068 90)
			(size 0.519938 1.4986)
			(layers "F.Cu" "F.Mask" "F.Paste")
			(net "M_B_CPU1_SA_CB<2>")
		)
		(pad "197" smd rect
			(at 2.050034 -19.12493 90)
			(size 0.519938 1.4986)
			(layers "F.Cu" "F.Mask" "F.Paste")
			(net "GND")
		)
		(pad "198" smd rect
			(at 2.050034 -18.275046 90)
			(size 0.519938 1.4986)
			(layers "F.Cu" "F.Mask" "F.Paste")
			(net "M_B_CPU1_SA_CB<3>")
		)
		(pad "199" smd rect
			(at 2.050034 -17.424908 90)
			(size 0.519938 1.4986)
			(layers "F.Cu" "F.Mask" "F.Paste")
			(net "GND")
		)
		(pad "200" smd rect
			(at 2.050034 -16.575024 90)
			(size 0.519938 1.4986)
			(layers "F.Cu" "F.Mask" "F.Paste")
			(net "M_B_CPU1_SA_DQS_DN<9>")
		)
		(pad "201" smd rect
			(at 2.050034 -15.724886 90)
			(size 0.519938 1.4986)
			(layers "F.Cu" "F.Mask" "F.Paste")
			(net "M_B_CPU1_SA_DQS_DP<9>")
		)
		(pad "202" smd rect
			(at 2.050034 -14.875002 90)
			(size 0.519938 1.4986)
			(layers "F.Cu" "F.Mask" "F.Paste")
			(net "GND")
		)
		(pad "203" smd rect
			(at 2.050034 -14.025118 90)
			(size 0.519938 1.4986)
			(layers "F.Cu" "F.Mask" "F.Paste")
			(net "M_B_CPU1_SA_CB<6>")
		)
		(pad "204" smd rect
			(at 2.050034 -13.17498 90)
			(size 0.519938 1.4986)
			(layers "F.Cu" "F.Mask" "F.Paste")
			(net "GND")
		)
		(pad "205" smd rect
			(at 2.050034 -12.325096 90)
			(size 0.519938 1.4986)
			(layers "F.Cu" "F.Mask" "F.Paste")
			(net "M_B_CPU1_SA_CB<7>")
		)
		(pad "206" smd rect
			(at 2.050034 -11.474958 90)
			(size 0.519938 1.4986)
			(layers "F.Cu" "F.Mask" "F.Paste")
			(net "GND")
		)
		(pad "207" smd rect
			(at 2.050034 -10.625074 90)
			(size 0.519938 1.4986)
			(layers "F.Cu" "F.Mask" "F.Paste")
			(net "M_B_CPU1_RESET_N")
		)
		(pad "208" smd rect
			(at 2.050034 -9.774936 90)
			(size 0.519938 1.4986)
			(layers "F.Cu" "F.Mask" "F.Paste")
			(net "GND")
		)
		(pad "209" smd rect
			(at 2.050034 -8.925052 90)
			(size 0.519938 1.4986)
			(layers "F.Cu" "F.Mask" "F.Paste")
			(net "M_B_CPU1_SA_CS_N<1>")
		)
		(pad "210" smd rect
			(at 2.050034 -8.074914 90)
			(size 0.519938 1.4986)
			(layers "F.Cu" "F.Mask" "F.Paste")
			(net "GND")
		)
		(pad "211" smd rect
			(at 2.050034 -7.22503 90)
			(size 0.519938 1.4986)
			(layers "F.Cu" "F.Mask" "F.Paste")
			(net "M_B_CPU1_SA_CA<1>")
		)
		(pad "212" smd rect
			(at 2.050034 -6.374892 90)
			(size 0.519938 1.4986)
			(layers "F.Cu" "F.Mask" "F.Paste")
			(net "GND")
		)
		(pad "213" smd rect
			(at 2.050034 -5.525008 90)
			(size 0.519938 1.4986)
			(layers "F.Cu" "F.Mask" "F.Paste")
			(net "M_B_CPU1_SA_CA<3>")
		)
		(pad "214" smd rect
			(at 2.050034 -4.675124 90)
			(size 0.519938 1.4986)
			(layers "F.Cu" "F.Mask" "F.Paste")
			(net "GND")
		)
		(pad "215" smd rect
			(at 2.050034 -3.824986 90)
			(size 0.519938 1.4986)
			(layers "F.Cu" "F.Mask" "F.Paste")
			(net "M_B_CPU1_SA_CA<5>")
		)
		(pad "216" smd rect
			(at 2.050034 -2.975102 90)
			(size 0.519938 1.4986)
			(layers "F.Cu" "F.Mask" "F.Paste")
			(net "GND")
		)
		(pad "217" smd rect
			(at 2.050034 -2.124964 90)
			(size 0.519938 1.4986)
			(layers "F.Cu" "F.Mask" "F.Paste")
			(net "M_B_CPU1_CLK_DP<0>")
		)
		(pad "218" smd rect
			(at 2.050034 -1.27508 90)
			(size 0.519938 1.4986)
			(layers "F.Cu" "F.Mask" "F.Paste")
			(net "M_B_CPU1_CLK_DN<0>")
		)
		(pad "219" smd rect
			(at 2.050034 -0.424942 90)
			(size 0.519938 1.4986)
			(layers "F.Cu" "F.Mask" "F.Paste")
			(net "GND")
		)
		(pad "220" smd rect
			(at 2.050034 5.525008 90)
			(size 0.519938 1.4986)
			(layers "F.Cu" "F.Mask" "F.Paste")
			(net "Net_2274")
		)
		(pad "221" smd rect
			(at 2.050034 6.374892 90)
			(size 0.519938 1.4986)
			(layers "F.Cu" "F.Mask" "F.Paste")
			(net "M_B_CPU1_SB_CA<1>")
		)
		(pad "222" smd rect
			(at 2.050034 7.22503 90)
			(size 0.519938 1.4986)
			(layers "F.Cu" "F.Mask" "F.Paste")
			(net "GND")
		)
		(pad "223" smd rect
			(at 2.050034 8.074914 90)
			(size 0.519938 1.4986)
			(layers "F.Cu" "F.Mask" "F.Paste")
			(net "M_B_CPU1_SB_CA<3>")
		)
		(pad "224" smd rect
			(at 2.050034 8.925052 90)
			(size 0.519938 1.4986)
			(layers "F.Cu" "F.Mask" "F.Paste")
			(net "GND")
		)
		(pad "225" smd rect
			(at 2.050034 9.774936 90)
			(size 0.519938 1.4986)
			(layers "F.Cu" "F.Mask" "F.Paste")
			(net "M_B_CPU1_SB_CA<5>")
		)
		(pad "226" smd rect
			(at 2.050034 10.625074 90)
			(size 0.519938 1.4986)
			(layers "F.Cu" "F.Mask" "F.Paste")
			(net "GND")
		)
		(pad "227" smd rect
			(at 2.050034 11.474958 90)
			(size 0.519938 1.4986)
			(layers "F.Cu" "F.Mask" "F.Paste")
			(net "M_B_CPU1_SB_PAR")
		)
		(pad "228" smd rect
			(at 2.050034 12.325096 90)
			(size 0.519938 1.4986)
			(layers "F.Cu" "F.Mask" "F.Paste")
			(net "GND")
		)
		(pad "229" smd rect
			(at 2.050034 13.17498 90)
			(size 0.519938 1.4986)
			(layers "F.Cu" "F.Mask" "F.Paste")
			(net "M_B_CPU1_SB_CS_N<1>")
		)
		(pad "230" smd rect
			(at 2.050034 14.025118 90)
			(size 0.519938 1.4986)
			(layers "F.Cu" "F.Mask" "F.Paste")
			(net "GND")
		)
	)
)
